(kicad_pcb
	(version 20260206)
	(generator "pcbnew")
	(generator_version "10.0")
	(general
		(thickness 1.6)
		(legacy_teardrops no)
	)
	(paper "A4")
	(title_block
		(title "v1-chassis-manager — T6M_CM_d_v01_1031_1645.brd")
		(comment 1 "Open CloudServer (Microsoft) / footprints 2511-2512 of 2512")
	)
	(layers
		(0 "F.Cu" signal "TOP")
		(4 "In1.Cu" signal "GND1")
		(6 "In2.Cu" signal "IN1")
		(8 "In3.Cu" signal "VCC1")
		(10 "In4.Cu" signal "VCC2")
		(12 "In5.Cu" signal "GND2")
		(14 "In6.Cu" signal "IN2")
		(16 "In7.Cu" signal "IN3")
		(18 "In8.Cu" signal "GND3")
		(2 "B.Cu" signal "BOTTOM")
		(9 "F.Adhes" user "F.Adhesive")
		(11 "B.Adhes" user "B.Adhesive")
		(13 "F.Paste" user "Package Geometry/Pastemask Top")
		(15 "B.Paste" user "Package Geometry/Pastemask Bottom")
		(5 "F.SilkS" user "Ref Des/Silkscreen Top")
		(7 "B.SilkS" user "Ref Des/Silkscreen Bottom")
		(1 "F.Mask" user "Board Geometry/Soldermask Top")
		(3 "B.Mask" user "Board Geometry/Soldermask Bottom")
		(17 "Dwgs.User" user "User.Drawings")
		(19 "Cmts.User" user "User.Comments")
		(21 "Eco1.User" user "User.Eco1")
		(23 "Eco2.User" user "User.Eco2")
		(25 "Edge.Cuts" user "Board Geometry/Outline")
		(27 "Margin" user)
		(31 "F.CrtYd" user "Package Geometry/Place Bound Top")
		(29 "B.CrtYd" user "Package Geometry/Place Bound Bottom")
		(35 "F.Fab" user "Ref Des/Assembly Top")
		(33 "B.Fab" user "Ref Des/Assembly Bottom")
	)
	(footprint ""
		(layer "B.Cu")
		(at 35.86988 -63.732156 180)
		(property "Reference" "C20"
			(at 2.232406 0.057658 0)
			(unlocked yes)
			(layer "B.SilkS")
			(effects
				(font
					(size 0.7874 0.5842)
					(thickness 0.1524)
				)
				(justify left mirror)
			)
		)
		(property "Value" ""
			(at 0 0 0)
			(layer "B.Fab")
			(effects
				(font
					(size 1.27 1.27)
				)
				(justify mirror)
			)
		)
		(duplicate_pad_numbers_are_jumpers no)
		(fp_line
			(start 0.7874 0.4064)
			(end 0.7874 -0.4064)
			(stroke
				(width 0.1524)
				(type default)
			)
			(layer "B.SilkS")
		)
		(fp_line
			(start 0.7874 -0.4064)
			(end -0.7874 -0.4064)
			(stroke
				(width 0.1524)
				(type default)
			)
			(layer "B.SilkS")
		)
		(fp_line
			(start 0 0.381)
			(end 0 -0.381)
			(stroke
				(width 0.1524)
				(type default)
			)
			(layer "B.SilkS")
		)
		(fp_line
			(start -0.7874 0.4064)
			(end 0.7874 0.4064)
			(stroke
				(width 0.1524)
				(type default)
			)
			(layer "B.SilkS")
		)
		(fp_line
			(start -0.7874 -0.4064)
			(end -0.7874 0.4064)
			(stroke
				(width 0.1524)
				(type default)
			)
			(layer "B.SilkS")
		)
		(fp_poly
			(pts
				(xy 0.5334 0.254) (xy 0.635 0.254) (xy 0.635 0.2286) (xy 0.635 -0.254) (xy 0.5334 -0.254) (xy 0.5334 -0.2794)
				(xy -0.5334 -0.2794) (xy -0.5334 -0.254) (xy -0.635 -0.254) (xy -0.635 0.254) (xy -0.5334 0.254)
				(xy -0.5334 0.2794) (xy 0.508 0.2794) (xy 0.5334 0.2794)
			)
			(stroke
				(width 0)
				(type default)
			)
			(fill no)
			(layer "B.CrtYd")
		)
		(pad "1" smd rect
			(at -0.40005 0)
			(size 0.4572 0.508)
			(layers "B.Cu" "B.Mask" "B.Paste")
			(net "P2E_CPU_NIC1_NODE1_TX_C_DN")
		)
		(pad "2" smd rect
			(at 0.40005 0)
			(size 0.4572 0.508)
			(layers "B.Cu" "B.Mask" "B.Paste")
			(net "P2E_CPU_NIC1_NODE1_TX_DN")
		)
	)
	(footprint ""
		(layer "B.Cu")
		(at 123.89358 -130.473196 -90)
		(property "Reference" ""
			(at 0 0 90)
			(layer "B.SilkS")
			(hide yes)
			(effects
				(font
					(size 1.27 1.27)
				)
				(justify mirror)
			)
		)
		(property "Value" ""
			(at 0 0 90)
			(layer "B.Fab")
			(effects
				(font
					(size 1.27 1.27)
				)
				(justify mirror)
			)
		)
		(duplicate_pad_numbers_are_jumpers no)
		(fp_poly
			(pts
				(arc
					(start 0 -1.4986)
					(mid 0 1.4986)
					(end 0 -1.4986)
				)
			)
			(stroke
				(width 0)
				(type default)
			)
			(fill no)
			(layer "B.CrtYd")
		)
		(pad "1" smd circle
			(at 0 0 90)
			(size 0.9906 0.9906)
			(layers "B.Cu" "B.Mask" "B.Paste")
			(net "Net_33")
		)
		(zone
			(layer "B.Cu")
			(hatch none 0.5)
			(connect_pads
				(clearance 0)
			)
			(min_thickness 0.25)
			(keepout
				(tracks not_allowed)
				(vias allowed)
				(pads allowed)
				(copperpour not_allowed)
				(footprints allowed)
			)
			(placement
				(enabled no)
				(sheetname "")
			)
			(fill
				(thermal_gap 0.5)
				(thermal_bridge_width 0.5)
				(island_removal_mode 0)
			)
			(polygon
				(pts
					(arc
						(start 125.51918 -130.473196)
						(mid 122.26798 -130.473196)
						(end 125.51918 -130.473196)
					)
				)
			)
		)
	)
)
